(kicad_pcb
	(version 20260206)
	(generator "pcbnew")
	(generator_version "10.0")
	(general
		(thickness 1.6)
		(legacy_teardrops no)
	)
	(paper "A4")
	(title_block
		(title "04192023_DAF0TMB3IC0_F0TG_MB_C_brd_V02_OCP.brd")
		(comment 1 "Grand Teton / footprints 1050-1056 of 8354")
	)
	(layers
		(0 "F.Cu" signal "TOP")
		(4 "In1.Cu" signal "GND")
		(6 "In2.Cu" signal "IN1")
		(8 "In3.Cu" signal "GND1")
		(10 "In4.Cu" signal "IN2")
		(12 "In5.Cu" signal "GND2")
		(14 "In6.Cu" signal "IN3")
		(16 "In7.Cu" signal "GND3")
		(18 "In8.Cu" signal "VCC")
		(20 "In9.Cu" signal "VCC1")
		(22 "In10.Cu" signal "GND4")
		(24 "In11.Cu" signal "IN4")
		(26 "In12.Cu" signal "GND5")
		(28 "In13.Cu" signal "IN5")
		(30 "In14.Cu" signal "GND6")
		(32 "In15.Cu" signal "IN6")
		(34 "In16.Cu" signal "GND7")
		(2 "B.Cu" signal "BOTTOM")
		(9 "F.Adhes" user "F.Adhesive")
		(11 "B.Adhes" user "B.Adhesive")
		(13 "F.Paste" user "Package Geometry/Pastemask Top")
		(15 "B.Paste" user "Package Geometry/Pastemask Bottom")
		(5 "F.SilkS" user "Ref Des/Silkscreen Top")
		(7 "B.SilkS" user "Ref Des/Silkscreen Bottom")
		(1 "F.Mask" user "Board Geometry/Soldermask Top")
		(3 "B.Mask" user "Board Geometry/Soldermask Bottom")
		(17 "Dwgs.User" user "User.Drawings")
		(19 "Cmts.User" user "User.Comments")
		(21 "Eco1.User" user "User.Eco1")
		(23 "Eco2.User" user "User.Eco2")
		(25 "Edge.Cuts" user "Board Geometry/Outline")
		(27 "Margin" user)
		(31 "F.CrtYd" user "Package Geometry/Place Bound Top")
		(29 "B.CrtYd" user "Package Geometry/Place Bound Bottom")
		(35 "F.Fab" user "Ref Des/Assembly Top")
		(33 "B.Fab" user "Ref Des/Assembly Bottom")
	)
	(footprint ""
		(layer "F.Cu")
		(at 16.20012 -76.144628 90)
		(property "Reference" "C1876"
			(at 0 0 90)
			(layer "F.SilkS")
			(hide yes)
			(effects
				(font
					(size 1.27 1.27)
				)
			)
		)
		(property "Value" ""
			(at 0 0 90)
			(layer "F.Fab")
			(effects
				(font
					(size 1.27 1.27)
				)
			)
		)
		(duplicate_pad_numbers_are_jumpers no)
		(fp_line
			(start 0.7874 -0.4064)
			(end 0.7874 0.4064)
			(stroke
				(width 0.1524)
				(type default)
			)
			(layer "F.SilkS")
		)
		(fp_line
			(start -0.7874 -0.4064)
			(end 0.7874 -0.4064)
			(stroke
				(width 0.1524)
				(type default)
			)
			(layer "F.SilkS")
		)
		(fp_line
			(start 0.7874 0.4064)
			(end -0.7874 0.4064)
			(stroke
				(width 0.1524)
				(type default)
			)
			(layer "F.SilkS")
		)
		(fp_line
			(start -0.7874 0.4064)
			(end -0.7874 -0.4064)
			(stroke
				(width 0.1524)
				(type default)
			)
			(layer "F.SilkS")
		)
		(fp_line
			(start -0.12065 -0.305054)
			(end -0.12065 -0.2794)
			(stroke
				(width 0.1)
				(type default)
			)
			(layer "F.Fab")
		)
		(fp_line
			(start -0.67945 -0.305054)
			(end -0.12065 -0.305054)
			(stroke
				(width 0.1)
				(type default)
			)
			(layer "F.Fab")
		)
		(fp_line
			(start 0.67945 -0.3048)
			(end 0.67945 0.3048)
			(stroke
				(width 0.1)
				(type default)
			)
			(layer "F.Fab")
		)
		(fp_line
			(start 0.12065 -0.3048)
			(end 0.67945 -0.3048)
			(stroke
				(width 0.1)
				(type default)
			)
			(layer "F.Fab")
		)
		(fp_line
			(start 0.12065 -0.2794)
			(end 0.12065 -0.3048)
			(stroke
				(width 0.1)
				(type default)
			)
			(layer "F.Fab")
		)
		(fp_line
			(start -0.12065 -0.2794)
			(end 0.12065 -0.2794)
			(stroke
				(width 0.1)
				(type default)
			)
			(layer "F.Fab")
		)
		(fp_line
			(start 0.120396 0.2794)
			(end -0.12065 0.2794)
			(stroke
				(width 0.1)
				(type default)
			)
			(layer "F.Fab")
		)
		(fp_line
			(start -0.12065 0.2794)
			(end -0.12065 0.3048)
			(stroke
				(width 0.1)
				(type default)
			)
			(layer "F.Fab")
		)
		(fp_line
			(start 0.67945 0.3048)
			(end 0.120396 0.3048)
			(stroke
				(width 0.1)
				(type default)
			)
			(layer "F.Fab")
		)
		(fp_line
			(start 0.120396 0.3048)
			(end 0.120396 0.2794)
			(stroke
				(width 0.1)
				(type default)
			)
			(layer "F.Fab")
		)
		(fp_line
			(start -0.12065 0.3048)
			(end -0.67945 0.3048)
			(stroke
				(width 0.1)
				(type default)
			)
			(layer "F.Fab")
		)
		(fp_line
			(start -0.67945 0.3048)
			(end -0.67945 -0.305054)
			(stroke
				(width 0.1)
				(type default)
			)
			(layer "F.Fab")
		)
		(pad "1" smd circle
			(at -0.40005 0 90)
			(size 0 0)
			(layers "F.Cu" "F.Mask" "F.Paste")
			(net "P3V3_AUX")
		)
		(pad "2" smd circle
			(at 0.40005 0 90)
			(size 0 0)
			(layers "F.Cu" "F.Mask" "F.Paste")
			(net "GND")
		)
	)
	(footprint ""
		(layer "F.Cu")
		(at 180.3908 -392.4554)
		(property "Reference" "R1416"
			(at 0 0 0)
			(layer "F.SilkS")
			(hide yes)
			(effects
				(font
					(size 1.27 1.27)
				)
			)
		)
		(property "Value" ""
			(at 0 0 0)
			(layer "F.Fab")
			(effects
				(font
					(size 1.27 1.27)
				)
			)
		)
		(duplicate_pad_numbers_are_jumpers no)
		(fp_line
			(start -0.32512 -0.175006)
			(end 0.32512 -0.175006)
			(stroke
				(width 0.1)
				(type default)
			)
			(layer "F.Fab")
		)
		(fp_line
			(start -0.32512 0.175006)
			(end -0.32512 -0.175006)
			(stroke
				(width 0.1)
				(type default)
			)
			(layer "F.Fab")
		)
		(fp_line
			(start 0.32512 -0.175006)
			(end 0.32512 0.175006)
			(stroke
				(width 0.1)
				(type default)
			)
			(layer "F.Fab")
		)
		(fp_line
			(start 0.32512 0.175006)
			(end -0.32512 0.175006)
			(stroke
				(width 0.1)
				(type default)
			)
			(layer "F.Fab")
		)
		(pad "1" smd rect
			(at -0.2667 0)
			(size 0.3048 0.381)
			(layers "F.Cu" "F.Mask" "F.Paste")
			(net "JTAG_TRST_RT_CPU1_P2_N")
		)
		(pad "2" smd rect
			(at 0.2667 0 180)
			(size 0.3048 0.381)
			(layers "F.Cu" "F.Mask" "F.Paste")
			(net "GND")
		)
	)
	(footprint ""
		(layer "F.Cu")
		(at 100.48367 -409.199588 180)
		(property "Reference" "C28"
			(at 0 0 180)
			(layer "F.SilkS")
			(hide yes)
			(effects
				(font
					(size 1.27 1.27)
				)
			)
		)
		(property "Value" ""
			(at 0 0 180)
			(layer "F.Fab")
			(effects
				(font
					(size 1.27 1.27)
				)
			)
		)
		(duplicate_pad_numbers_are_jumpers no)
		(fp_line
			(start 0.7874 0.4064)
			(end -0.7874 0.4064)
			(stroke
				(width 0.1524)
				(type default)
			)
			(layer "F.SilkS")
		)
		(fp_line
			(start 0.7874 -0.4064)
			(end 0.7874 0.4064)
			(stroke
				(width 0.1524)
				(type default)
			)
			(layer "F.SilkS")
		)
		(fp_line
			(start -0.7874 0.4064)
			(end -0.7874 -0.4064)
			(stroke
				(width 0.1524)
				(type default)
			)
			(layer "F.SilkS")
		)
		(fp_line
			(start -0.7874 -0.4064)
			(end 0.7874 -0.4064)
			(stroke
				(width 0.1524)
				(type default)
			)
			(layer "F.SilkS")
		)
		(fp_line
			(start 0.67945 0.3048)
			(end 0.120396 0.3048)
			(stroke
				(width 0.1)
				(type default)
			)
			(layer "F.Fab")
		)
		(fp_line
			(start 0.67945 -0.3048)
			(end 0.67945 0.3048)
			(stroke
				(width 0.1)
				(type default)
			)
			(layer "F.Fab")
		)
		(fp_line
			(start 0.12065 -0.2794)
			(end 0.12065 -0.3048)
			(stroke
				(width 0.1)
				(type default)
			)
			(layer "F.Fab")
		)
		(fp_line
			(start 0.12065 -0.3048)
			(end 0.67945 -0.3048)
			(stroke
				(width 0.1)
				(type default)
			)
			(layer "F.Fab")
		)
		(fp_line
			(start 0.120396 0.3048)
			(end 0.120396 0.2794)
			(stroke
				(width 0.1)
				(type default)
			)
			(layer "F.Fab")
		)
		(fp_line
			(start 0.120396 0.2794)
			(end -0.12065 0.2794)
			(stroke
				(width 0.1)
				(type default)
			)
			(layer "F.Fab")
		)
		(fp_line
			(start -0.12065 0.3048)
			(end -0.67945 0.3048)
			(stroke
				(width 0.1)
				(type default)
			)
			(layer "F.Fab")
		)
		(fp_line
			(start -0.12065 0.2794)
			(end -0.12065 0.3048)
			(stroke
				(width 0.1)
				(type default)
			)
			(layer "F.Fab")
		)
		(fp_line
			(start -0.12065 -0.2794)
			(end 0.12065 -0.2794)
			(stroke
				(width 0.1)
				(type default)
			)
			(layer "F.Fab")
		)
		(fp_line
			(start -0.12065 -0.305054)
			(end -0.12065 -0.2794)
			(stroke
				(width 0.1)
				(type default)
			)
			(layer "F.Fab")
		)
		(fp_line
			(start -0.67945 0.3048)
			(end -0.67945 -0.305054)
			(stroke
				(width 0.1)
				(type default)
			)
			(layer "F.Fab")
		)
		(fp_line
			(start -0.67945 -0.305054)
			(end -0.12065 -0.305054)
			(stroke
				(width 0.1)
				(type default)
			)
			(layer "F.Fab")
		)
		(pad "1" smd circle
			(at -0.40005 0 180)
			(size 0 0)
			(layers "F.Cu" "F.Mask" "F.Paste")
			(net "P3V3_9ZXL045_P1_VDD")
		)
		(pad "2" smd circle
			(at 0.40005 0 180)
			(size 0 0)
			(layers "F.Cu" "F.Mask" "F.Paste")
			(net "GND")
		)
	)
	(footprint ""
		(layer "F.Cu")
		(at 316.23 -362.839 90)
		(property "Reference" "PC74"
			(at 0 0 90)
			(layer "F.SilkS")
			(hide yes)
			(effects
				(font
					(size 1.27 1.27)
				)
			)
		)
		(property "Value" ""
			(at 0 0 90)
			(layer "F.Fab")
			(effects
				(font
					(size 1.27 1.27)
				)
			)
		)
		(duplicate_pad_numbers_are_jumpers no)
		(fp_line
			(start 0.7874 -0.4064)
			(end 0.7874 0.4064)
			(stroke
				(width 0.1524)
				(type default)
			)
			(layer "F.SilkS")
		)
		(fp_line
			(start -0.7874 -0.4064)
			(end 0.7874 -0.4064)
			(stroke
				(width 0.1524)
				(type default)
			)
			(layer "F.SilkS")
		)
		(fp_line
			(start 0.7874 0.4064)
			(end -0.7874 0.4064)
			(stroke
				(width 0.1524)
				(type default)
			)
			(layer "F.SilkS")
		)
		(fp_line
			(start -0.7874 0.4064)
			(end -0.7874 -0.4064)
			(stroke
				(width 0.1524)
				(type default)
			)
			(layer "F.SilkS")
		)
		(fp_line
			(start -0.12065 -0.305054)
			(end -0.12065 -0.2794)
			(stroke
				(width 0.1)
				(type default)
			)
			(layer "F.Fab")
		)
		(fp_line
			(start -0.67945 -0.305054)
			(end -0.12065 -0.305054)
			(stroke
				(width 0.1)
				(type default)
			)
			(layer "F.Fab")
		)
		(fp_line
			(start 0.67945 -0.3048)
			(end 0.67945 0.3048)
			(stroke
				(width 0.1)
				(type default)
			)
			(layer "F.Fab")
		)
		(fp_line
			(start 0.12065 -0.3048)
			(end 0.67945 -0.3048)
			(stroke
				(width 0.1)
				(type default)
			)
			(layer "F.Fab")
		)
		(fp_line
			(start 0.12065 -0.2794)
			(end 0.12065 -0.3048)
			(stroke
				(width 0.1)
				(type default)
			)
			(layer "F.Fab")
		)
		(fp_line
			(start -0.12065 -0.2794)
			(end 0.12065 -0.2794)
			(stroke
				(width 0.1)
				(type default)
			)
			(layer "F.Fab")
		)
		(fp_line
			(start 0.120396 0.2794)
			(end -0.12065 0.2794)
			(stroke
				(width 0.1)
				(type default)
			)
			(layer "F.Fab")
		)
		(fp_line
			(start -0.12065 0.2794)
			(end -0.12065 0.3048)
			(stroke
				(width 0.1)
				(type default)
			)
			(layer "F.Fab")
		)
		(fp_line
			(start 0.67945 0.3048)
			(end 0.120396 0.3048)
			(stroke
				(width 0.1)
				(type default)
			)
			(layer "F.Fab")
		)
		(fp_line
			(start 0.120396 0.3048)
			(end 0.120396 0.2794)
			(stroke
				(width 0.1)
				(type default)
			)
			(layer "F.Fab")
		)
		(fp_line
			(start -0.12065 0.3048)
			(end -0.67945 0.3048)
			(stroke
				(width 0.1)
				(type default)
			)
			(layer "F.Fab")
		)
		(fp_line
			(start -0.67945 0.3048)
			(end -0.67945 -0.305054)
			(stroke
				(width 0.1)
				(type default)
			)
			(layer "F.Fab")
		)
		(pad "1" smd circle
			(at -0.40005 0 90)
			(size 0 0)
			(layers "F.Cu" "F.Mask" "F.Paste")
			(net "PVDDCR_CPU1_P0_VINSEN")
		)
		(pad "2" smd circle
			(at 0.40005 0 90)
			(size 0 0)
			(layers "F.Cu" "F.Mask" "F.Paste")
			(net "GND")
		)
	)
	(footprint ""
		(layer "F.Cu")
		(at 415.119058 -357.61676 90)
		(property "Reference" "PR121"
			(at 0 0 90)
			(layer "F.SilkS")
			(hide yes)
			(effects
				(font
					(size 1.27 1.27)
				)
			)
		)
		(property "Value" ""
			(at 0 0 90)
			(layer "F.Fab")
			(effects
				(font
					(size 1.27 1.27)
				)
			)
		)
		(duplicate_pad_numbers_are_jumpers no)
		(fp_line
			(start 0.7874 -0.4064)
			(end 0.7874 0.4064)
			(stroke
				(width 0.1524)
				(type default)
			)
			(layer "F.SilkS")
		)
		(fp_line
			(start -0.7874 -0.4064)
			(end 0.7874 -0.4064)
			(stroke
				(width 0.1524)
				(type default)
			)
			(layer "F.SilkS")
		)
		(fp_line
			(start 0.7874 0.4064)
			(end -0.7874 0.4064)
			(stroke
				(width 0.1524)
				(type default)
			)
			(layer "F.SilkS")
		)
		(fp_line
			(start -0.7874 0.4064)
			(end -0.7874 -0.4064)
			(stroke
				(width 0.1524)
				(type default)
			)
			(layer "F.SilkS")
		)
		(fp_line
			(start -0.12065 -0.305054)
			(end -0.12065 -0.2794)
			(stroke
				(width 0.1)
				(type default)
			)
			(layer "F.Fab")
		)
		(fp_line
			(start -0.67945 -0.305054)
			(end -0.12065 -0.305054)
			(stroke
				(width 0.1)
				(type default)
			)
			(layer "F.Fab")
		)
		(fp_line
			(start 0.67945 -0.3048)
			(end 0.67945 0.3048)
			(stroke
				(width 0.1)
				(type default)
			)
			(layer "F.Fab")
		)
		(fp_line
			(start 0.12065 -0.3048)
			(end 0.67945 -0.3048)
			(stroke
				(width 0.1)
				(type default)
			)
			(layer "F.Fab")
		)
		(fp_line
			(start 0.12065 -0.2794)
			(end 0.12065 -0.3048)
			(stroke
				(width 0.1)
				(type default)
			)
			(layer "F.Fab")
		)
		(fp_line
			(start -0.12065 -0.2794)
			(end 0.12065 -0.2794)
			(stroke
				(width 0.1)
				(type default)
			)
			(layer "F.Fab")
		)
		(fp_line
			(start 0.120396 0.2794)
			(end -0.12065 0.2794)
			(stroke
				(width 0.1)
				(type default)
			)
			(layer "F.Fab")
		)
		(fp_line
			(start -0.12065 0.2794)
			(end -0.12065 0.3048)
			(stroke
				(width 0.1)
				(type default)
			)
			(layer "F.Fab")
		)
		(fp_line
			(start 0.67945 0.3048)
			(end 0.120396 0.3048)
			(stroke
				(width 0.1)
				(type default)
			)
			(layer "F.Fab")
		)
		(fp_line
			(start 0.120396 0.3048)
			(end 0.120396 0.2794)
			(stroke
				(width 0.1)
				(type default)
			)
			(layer "F.Fab")
		)
		(fp_line
			(start -0.12065 0.3048)
			(end -0.67945 0.3048)
			(stroke
				(width 0.1)
				(type default)
			)
			(layer "F.Fab")
		)
		(fp_line
			(start -0.67945 0.3048)
			(end -0.67945 -0.305054)
			(stroke
				(width 0.1)
				(type default)
			)
			(layer "F.Fab")
		)
		(pad "1" smd circle
			(at -0.40005 0 90)
			(size 0 0)
			(layers "F.Cu" "F.Mask" "F.Paste")
			(net "VSENSE_PVDD11_S3_P0_DP")
		)
		(pad "2" smd circle
			(at 0.40005 0 90)
			(size 0 0)
			(layers "F.Cu" "F.Mask" "F.Paste")
			(net "VSENSE_PVDD11_S3_P0_R")
		)
	)
	(footprint ""
		(layer "F.Cu")
		(at 296.670984 -343.712038 180)
		(property "Reference" "PC158"
			(at 0 0 180)
			(layer "F.SilkS")
			(hide yes)
			(effects
				(font
					(size 1.27 1.27)
				)
			)
		)
		(property "Value" ""
			(at 0 0 180)
			(layer "F.Fab")
			(effects
				(font
					(size 1.27 1.27)
				)
			)
		)
		(duplicate_pad_numbers_are_jumpers no)
		(fp_line
			(start 0.7874 0.4064)
			(end -0.7874 0.4064)
			(stroke
				(width 0.1524)
				(type default)
			)
			(layer "F.SilkS")
		)
		(fp_line
			(start 0.7874 -0.4064)
			(end 0.7874 0.4064)
			(stroke
				(width 0.1524)
				(type default)
			)
			(layer "F.SilkS")
		)
		(fp_line
			(start -0.7874 0.4064)
			(end -0.7874 -0.4064)
			(stroke
				(width 0.1524)
				(type default)
			)
			(layer "F.SilkS")
		)
		(fp_line
			(start -0.7874 -0.4064)
			(end 0.7874 -0.4064)
			(stroke
				(width 0.1524)
				(type default)
			)
			(layer "F.SilkS")
		)
		(fp_line
			(start 0.67945 0.3048)
			(end 0.120396 0.3048)
			(stroke
				(width 0.1)
				(type default)
			)
			(layer "F.Fab")
		)
		(fp_line
			(start 0.67945 -0.3048)
			(end 0.67945 0.3048)
			(stroke
				(width 0.1)
				(type default)
			)
			(layer "F.Fab")
		)
		(fp_line
			(start 0.12065 -0.2794)
			(end 0.12065 -0.3048)
			(stroke
				(width 0.1)
				(type default)
			)
			(layer "F.Fab")
		)
		(fp_line
			(start 0.12065 -0.3048)
			(end 0.67945 -0.3048)
			(stroke
				(width 0.1)
				(type default)
			)
			(layer "F.Fab")
		)
		(fp_line
			(start 0.120396 0.3048)
			(end 0.120396 0.2794)
			(stroke
				(width 0.1)
				(type default)
			)
			(layer "F.Fab")
		)
		(fp_line
			(start 0.120396 0.2794)
			(end -0.12065 0.2794)
			(stroke
				(width 0.1)
				(type default)
			)
			(layer "F.Fab")
		)
		(fp_line
			(start -0.12065 0.3048)
			(end -0.67945 0.3048)
			(stroke
				(width 0.1)
				(type default)
			)
			(layer "F.Fab")
		)
		(fp_line
			(start -0.12065 0.2794)
			(end -0.12065 0.3048)
			(stroke
				(width 0.1)
				(type default)
			)
			(layer "F.Fab")
		)
		(fp_line
			(start -0.12065 -0.2794)
			(end 0.12065 -0.2794)
			(stroke
				(width 0.1)
				(type default)
			)
			(layer "F.Fab")
		)
		(fp_line
			(start -0.12065 -0.305054)
			(end -0.12065 -0.2794)
			(stroke
				(width 0.1)
				(type default)
			)
			(layer "F.Fab")
		)
		(fp_line
			(start -0.67945 0.3048)
			(end -0.67945 -0.305054)
			(stroke
				(width 0.1)
				(type default)
			)
			(layer "F.Fab")
		)
		(fp_line
			(start -0.67945 -0.305054)
			(end -0.12065 -0.305054)
			(stroke
				(width 0.1)
				(type default)
			)
			(layer "F.Fab")
		)
		(pad "1" smd circle
			(at -0.40005 0 180)
			(size 0 0)
			(layers "F.Cu" "F.Mask" "F.Paste")
			(net "SW_PVDDIO_P0_SW1")
		)
		(pad "2" smd circle
			(at 0.40005 0 180)
			(size 0 0)
			(layers "F.Cu" "F.Mask" "F.Paste")
			(net "SW_PVDDIO_P0_SW1_RC")
		)
	)
	(footprint ""
		(layer "F.Cu")
		(at 138.426952 -58.532014)
		(property "Reference" "R1742"
			(at 0 0 0)
			(layer "F.SilkS")
			(hide yes)
			(effects
				(font
					(size 1.27 1.27)
				)
			)
		)
		(property "Value" ""
			(at 0 0 0)
			(layer "F.Fab")
			(effects
				(font
					(size 1.27 1.27)
				)
			)
		)
		(duplicate_pad_numbers_are_jumpers no)
		(fp_line
			(start -0.7874 -0.4064)
			(end 0.7874 -0.4064)
			(stroke
				(width 0.1524)
				(type default)
			)
			(layer "F.SilkS")
		)
		(fp_line
			(start -0.7874 0.4064)
			(end -0.7874 -0.4064)
			(stroke
				(width 0.1524)
				(type default)
			)
			(layer "F.SilkS")
		)
		(fp_line
			(start 0.7874 -0.4064)
			(end 0.7874 0.4064)
			(stroke
				(width 0.1524)
				(type default)
			)
			(layer "F.SilkS")
		)
		(fp_line
			(start 0.7874 0.4064)
			(end -0.7874 0.4064)
			(stroke
				(width 0.1524)
				(type default)
			)
			(layer "F.SilkS")
		)
		(fp_line
			(start -0.67945 -0.305054)
			(end -0.12065 -0.305054)
			(stroke
				(width 0.1)
				(type default)
			)
			(layer "F.Fab")
		)
		(fp_line
			(start -0.67945 0.3048)
			(end -0.67945 -0.305054)
			(stroke
				(width 0.1)
				(type default)
			)
			(layer "F.Fab")
		)
		(fp_line
			(start -0.12065 -0.305054)
			(end -0.12065 -0.2794)
			(stroke
				(width 0.1)
				(type default)
			)
			(layer "F.Fab")
		)
		(fp_line
			(start -0.12065 -0.2794)
			(end 0.12065 -0.2794)
			(stroke
				(width 0.1)
				(type default)
			)
			(layer "F.Fab")
		)
		(fp_line
			(start -0.12065 0.2794)
			(end -0.12065 0.3048)
			(stroke
				(width 0.1)
				(type default)
			)
			(layer "F.Fab")
		)
		(fp_line
			(start -0.12065 0.3048)
			(end -0.67945 0.3048)
			(stroke
				(width 0.1)
				(type default)
			)
			(layer "F.Fab")
		)
		(fp_line
			(start 0.120396 0.2794)
			(end -0.12065 0.2794)
			(stroke
				(width 0.1)
				(type default)
			)
			(layer "F.Fab")
		)
		(fp_line
			(start 0.120396 0.3048)
			(end 0.120396 0.2794)
			(stroke
				(width 0.1)
				(type default)
			)
			(layer "F.Fab")
		)
		(fp_line
			(start 0.12065 -0.3048)
			(end 0.67945 -0.3048)
			(stroke
				(width 0.1)
				(type default)
			)
			(layer "F.Fab")
		)
		(fp_line
			(start 0.12065 -0.2794)
			(end 0.12065 -0.3048)
			(stroke
				(width 0.1)
				(type default)
			)
			(layer "F.Fab")
		)
		(fp_line
			(start 0.67945 -0.3048)
			(end 0.67945 0.3048)
			(stroke
				(width 0.1)
				(type default)
			)
			(layer "F.Fab")
		)
		(fp_line
			(start 0.67945 0.3048)
			(end 0.120396 0.3048)
			(stroke
				(width 0.1)
				(type default)
			)
			(layer "F.Fab")
		)
		(pad "1" smd circle
			(at -0.40005 0)
			(size 0 0)
			(layers "F.Cu" "F.Mask" "F.Paste")
			(net "JTAG_SCM_PLD_R_TDI")
		)
		(pad "2" smd circle
			(at 0.40005 0)
			(size 0 0)
			(layers "F.Cu" "F.Mask" "F.Paste")
			(net "JTAG_SCM_PLD_TDI")
		)
	)
)
